(kicad_pcb
	(version 20241229)
	(generator "pcbnew")
	(generator_version "9.0")
	(general
		(thickness 1.599998)
		(legacy_teardrops no)
	)
	(paper "A4")
	(title_block
		(title "Artix - Datacenter Secure Control Module (DC-SCM)")
		(date "2024-11-06")
		(rev "1.1.3")
		(comment 9 "footprints 133-133 of 544")
	)
	(layers
		(0 "F.Cu" signal)
		(4 "In1.Cu" signal)
		(6 "In2.Cu" signal)
		(8 "In3.Cu" signal)
		(10 "In4.Cu" signal)
		(12 "In5.Cu" signal)
		(14 "In6.Cu" signal)
		(2 "B.Cu" signal)
		(9 "F.Adhes" user "F.Adhesive")
		(11 "B.Adhes" user "B.Adhesive")
		(13 "F.Paste" user)
		(15 "B.Paste" user)
		(5 "F.SilkS" user "F.Silkscreen")
		(7 "B.SilkS" user "B.Silkscreen")
		(1 "F.Mask" user)
		(3 "B.Mask" user)
		(17 "Dwgs.User" user "User.Drawings")
		(19 "Cmts.User" user "User.Comments")
		(21 "Eco1.User" user "User.Eco1")
		(23 "Eco2.User" user "User.Eco2")
		(25 "Edge.Cuts" user)
		(27 "Margin" user)
		(31 "F.CrtYd" user "F.Courtyard")
		(29 "B.CrtYd" user "B.Courtyard")
		(35 "F.Fab" user)
		(33 "B.Fab" user)
	)
	(footprint "antmicro-footprints:R_0402_1005Metric"
		(layer "F.Cu")
		(at 83.19 123.645 -90)
		(descr "Resistor SMD 0402")
		(tags "resistor SMD 0402")
		(property "Reference" "R144"
			(at 0.855 -0.31 90)
			(layer "F.SilkS")
			(effects
				(font
					(size 0.7 0.7)
					(thickness 0.15)
				)
				(justify right bottom)
			)
		)
		(property "Value" "R_0R_0402"
			(at 0 1.4 90)
			(layer "F.Fab")
			(effects
				(font
					(size 0.7 0.7)
					(thickness 0.15)
				)
				(justify right bottom)
			)
		)
		(property "Datasheet" "https://industrial.panasonic.com/cdbs/www-data/pdf/RDA0000/AOA0000C301.pdf"
			(at 0 0 270)
			(layer "F.Fab")
			(hide yes)
			(effects
				(font
					(size 1.27 1.27)
					(thickness 0.15)
				)
			)
		)
		(property "Description" "SMD Chip Resistor, Jumper, 0 ohm, 100 mW, 0402 [1005 Metric], Thick Film, General Purpose"
			(at 0 0 270)
			(layer "F.Fab")
			(hide yes)
			(effects
				(font
					(size 1.27 1.27)
					(thickness 0.15)
				)
			)
		)
		(property "Author" "Antmicro"
			(at -40.455 206.835 0)
			(layer "F.Fab")
			(hide yes)
			(effects
				(font
					(size 1 1)
					(thickness 0.15)
				)
			)
		)
		(property "Current" "1A"
			(at -40.455 206.835 0)
			(layer "F.Fab")
			(hide yes)
			(effects
				(font
					(size 1 1)
					(thickness 0.15)
				)
			)
		)
		(property "License" "Apache-2.0"
			(at -40.455 206.835 0)
			(layer "F.Fab")
			(hide yes)
			(effects
				(font
					(size 1 1)
					(thickness 0.15)
				)
			)
		)
		(property "MPN" "ERJ2GE0R00X"
			(at -40.455 206.835 0)
			(layer "F.Fab")
			(hide yes)
			(effects
				(font
					(size 1 1)
					(thickness 0.15)
				)
			)
		)
		(property "Manufacturer" "Panasonic"
			(at -40.455 206.835 0)
			(layer "F.Fab")
			(hide yes)
			(effects
				(font
					(size 1 1)
					(thickness 0.15)
				)
			)
		)
		(property "Tolerance" "~"
			(at -40.455 206.835 0)
			(layer "F.Fab")
			(hide yes)
			(effects
				(font
					(size 1 1)
					(thickness 0.15)
				)
			)
		)
		(property "Val" "0R"
			(at -40.455 206.835 0)
			(layer "F.Fab")
			(hide yes)
			(effects
				(font
					(size 1 1)
					(thickness 0.15)
				)
			)
		)
		(sheetname "/Edge connector/")
		(sheetfile "edge-connector.kicad_sch")
		(attr smd)
		(fp_rect
			(start -0.925 -0.47)
			(end 0.925 0.47)
			(stroke
				(width 0.05)
				(type default)
			)
			(fill no)
			(layer "F.CrtYd")
		)
		(fp_rect
			(start -0.5 -0.25)
			(end 0.5 0.25)
			(stroke
				(width 0.15)
				(type solid)
			)
			(fill no)
			(layer "F.Fab")
		)
		(pad "1" smd roundrect
			(at -0.48 0 270)
			(size 0.59 0.64)
			(layers "F.Cu" "F.Mask" "F.Paste")
			(roundrect_rratio 0.25)
			(net 523 "SPI0_MOSI_R")
			(pintype "passive")
		)
		(pad "2" smd roundrect
			(at 0.48 0 270)
			(size 0.59 0.64)
			(layers "F.Cu" "F.Mask" "F.Paste")
			(roundrect_rratio 0.25)
			(net 57 "SPI0_MOSI")
			(pintype "passive")
		)
	)
)
